# T6G (Grand Teton) — schematic netlist excerpt (pin names and nets, part order shuffled) for the footprints in the layout excerpt that follows; sources: Cadence DE-HDL packaged netlist, KiCad conversion of 04192023_DAF0TMB3IC0_F0TG_MB_C_brd_V02_OCP.brd

R347  Q_RES  33.2 1% CHIP  pkg 0402LF  page 151 : A = SMB_SML1_PMBUS_HSC_SCL ; B = SMB_SML1_PMBUS_HSC_R1_SCL
R6222  Q_RES  10K 1% CHIP  pkg 0402LF  page 176 : A = P3V3_AUX ; B = USB_CPU0_ADD_A0

(kicad_pcb
	(version 20260206)
	(generator "pcbnew")
	(generator_version "10.0")
	(general
		(thickness 1.6)
		(legacy_teardrops no)
	)
	(paper "A4")
	(title_block
		(title "04192023_DAF0TMB3IC0_F0TG_MB_C_brd_V02_OCP.brd")
		(comment 1 "Grand Teton / footprints 2647-2648 of 8354")
	)
	(layers
		(0 "F.Cu" signal "TOP")
		(4 "In1.Cu" signal "GND")
		(6 "In2.Cu" signal "IN1")
		(8 "In3.Cu" signal "GND1")
		(10 "In4.Cu" signal "IN2")
		(12 "In5.Cu" signal "GND2")
		(14 "In6.Cu" signal "IN3")
		(16 "In7.Cu" signal "GND3")
		(18 "In8.Cu" signal "VCC")
		(20 "In9.Cu" signal "VCC1")
		(22 "In10.Cu" signal "GND4")
		(24 "In11.Cu" signal "IN4")
		(26 "In12.Cu" signal "GND5")
		(28 "In13.Cu" signal "IN5")
		(30 "In14.Cu" signal "GND6")
		(32 "In15.Cu" signal "IN6")
		(34 "In16.Cu" signal "GND7")
		(2 "B.Cu" signal "BOTTOM")
		(9 "F.Adhes" user "F.Adhesive")
		(11 "B.Adhes" user "B.Adhesive")
		(13 "F.Paste" user "Package Geometry/Pastemask Top")
		(15 "B.Paste" user "Package Geometry/Pastemask Bottom")
		(5 "F.SilkS" user "Ref Des/Silkscreen Top")
		(7 "B.SilkS" user "Ref Des/Silkscreen Bottom")
		(1 "F.Mask" user "Board Geometry/Soldermask Top")
		(3 "B.Mask" user "Board Geometry/Soldermask Bottom")
		(17 "Dwgs.User" user "User.Drawings")
		(19 "Cmts.User" user "User.Comments")
		(21 "Eco1.User" user "User.Eco1")
		(23 "Eco2.User" user "User.Eco2")
		(25 "Edge.Cuts" user "Board Geometry/Outline")
		(27 "Margin" user)
		(31 "F.CrtYd" user "Package Geometry/Place Bound Top")
		(29 "B.CrtYd" user "Package Geometry/Place Bound Bottom")
		(35 "F.Fab" user "Ref Des/Assembly Top")
		(33 "B.Fab" user "Ref Des/Assembly Bottom")
	)
	(footprint ""
		(layer "F.Cu")
		(at 105.84561 -67.60591)
		(property "Reference" "R6222"
			(at 0 0 0)
			(layer "F.SilkS")
			(hide yes)
			(effects
				(font
					(size 1.27 1.27)
				)
			)
		)
		(property "Value" ""
			(at 0 0 0)
			(layer "F.Fab")
			(effects
				(font
					(size 1.27 1.27)
				)
			)
		)
		(duplicate_pad_numbers_are_jumpers no)
		(fp_line
			(start -0.7874 -0.4064)
			(end 0.7874 -0.4064)
			(stroke
				(width 0.1524)
				(type default)
			)
			(layer "F.SilkS")
		)
		(fp_line
			(start -0.7874 0.4064)
			(end -0.7874 -0.4064)
			(stroke
				(width 0.1524)
				(type default)
			)
			(layer "F.SilkS")
		)
		(fp_line
			(start 0.7874 -0.4064)
			(end 0.7874 0.4064)
			(stroke
				(width 0.1524)
				(type default)
			)
			(layer "F.SilkS")
		)
		(fp_line
			(start 0.7874 0.4064)
			(end -0.7874 0.4064)
			(stroke
				(width 0.1524)
				(type default)
			)
			(layer "F.SilkS")
		)
		(fp_line
			(start -0.67945 -0.305054)
			(end -0.12065 -0.305054)
			(stroke
				(width 0.1)
				(type default)
			)
			(layer "F.Fab")
		)
		(fp_line
			(start -0.67945 0.3048)
			(end -0.67945 -0.305054)
			(stroke
				(width 0.1)
				(type default)
			)
			(layer "F.Fab")
		)
		(fp_line
			(start -0.12065 -0.305054)
			(end -0.12065 -0.2794)
			(stroke
				(width 0.1)
				(type default)
			)
			(layer "F.Fab")
		)
		(fp_line
			(start -0.12065 -0.2794)
			(end 0.12065 -0.2794)
			(stroke
				(width 0.1)
				(type default)
			)
			(layer "F.Fab")
		)
		(fp_line
			(start -0.12065 0.2794)
			(end -0.12065 0.3048)
			(stroke
				(width 0.1)
				(type default)
			)
			(layer "F.Fab")
		)
		(fp_line
			(start -0.12065 0.3048)
			(end -0.67945 0.3048)
			(stroke
				(width 0.1)
				(type default)
			)
			(layer "F.Fab")
		)
		(fp_line
			(start 0.120396 0.2794)
			(end -0.12065 0.2794)
			(stroke
				(width 0.1)
				(type default)
			)
			(layer "F.Fab")
		)
		(fp_line
			(start 0.120396 0.3048)
			(end 0.120396 0.2794)
			(stroke
				(width 0.1)
				(type default)
			)
			(layer "F.Fab")
		)
		(fp_line
			(start 0.12065 -0.3048)
			(end 0.67945 -0.3048)
			(stroke
				(width 0.1)
				(type default)
			)
			(layer "F.Fab")
		)
		(fp_line
			(start 0.12065 -0.2794)
			(end 0.12065 -0.3048)
			(stroke
				(width 0.1)
				(type default)
			)
			(layer "F.Fab")
		)
		(fp_line
			(start 0.67945 -0.3048)
			(end 0.67945 0.3048)
			(stroke
				(width 0.1)
				(type default)
			)
			(layer "F.Fab")
		)
		(fp_line
			(start 0.67945 0.3048)
			(end 0.120396 0.3048)
			(stroke
				(width 0.1)
				(type default)
			)
			(layer "F.Fab")
		)
		(pad "1" smd circle
			(at -0.40005 0)
			(size 0 0)
			(layers "F.Cu" "F.Mask" "F.Paste")
			(net "P3V3_AUX")
		)
		(pad "2" smd circle
			(at 0.40005 0)
			(size 0 0)
			(layers "F.Cu" "F.Mask" "F.Paste")
			(net "USB_CPU0_ADD_A0")
		)
	)
	(footprint ""
		(layer "F.Cu")
		(at 177.984912 -412.257748 180)
		(property "Reference" "R347"
			(at 0 0 180)
			(layer "F.SilkS")
			(hide yes)
			(effects
				(font
					(size 1.27 1.27)
				)
			)
		)
		(property "Value" ""
			(at 0 0 180)
			(layer "F.Fab")
			(effects
				(font
					(size 1.27 1.27)
				)
			)
		)
		(duplicate_pad_numbers_are_jumpers no)
		(fp_line
			(start 0.7874 0.4064)
			(end -0.7874 0.4064)
			(stroke
				(width 0.1524)
				(type default)
			)
			(layer "F.SilkS")
		)
		(fp_line
			(start 0.7874 -0.4064)
			(end 0.7874 0.4064)
			(stroke
				(width 0.1524)
				(type default)
			)
			(layer "F.SilkS")
		)
		(fp_line
			(start -0.7874 0.4064)
			(end -0.7874 -0.4064)
			(stroke
				(width 0.1524)
				(type default)
			)
			(layer "F.SilkS")
		)
		(fp_line
			(start -0.7874 -0.4064)
			(end 0.7874 -0.4064)
			(stroke
				(width 0.1524)
				(type default)
			)
			(layer "F.SilkS")
		)
		(fp_line
			(start 0.67945 0.3048)
			(end 0.120396 0.3048)
			(stroke
				(width 0.1)
				(type default)
			)
			(layer "F.Fab")
		)
		(fp_line
			(start 0.67945 -0.3048)
			(end 0.67945 0.3048)
			(stroke
				(width 0.1)
				(type default)
			)
			(layer "F.Fab")
		)
		(fp_line
			(start 0.12065 -0.2794)
			(end 0.12065 -0.3048)
			(stroke
				(width 0.1)
				(type default)
			)
			(layer "F.Fab")
		)
		(fp_line
			(start 0.12065 -0.3048)
			(end 0.67945 -0.3048)
			(stroke
				(width 0.1)
				(type default)
			)
			(layer "F.Fab")
		)
		(fp_line
			(start 0.120396 0.3048)
			(end 0.120396 0.2794)
			(stroke
				(width 0.1)
				(type default)
			)
			(layer "F.Fab")
		)
		(fp_line
			(start 0.120396 0.2794)
			(end -0.12065 0.2794)
			(stroke
				(width 0.1)
				(type default)
			)
			(layer "F.Fab")
		)
		(fp_line
			(start -0.12065 0.3048)
			(end -0.67945 0.3048)
			(stroke
				(width 0.1)
				(type default)
			)
			(layer "F.Fab")
		)
		(fp_line
			(start -0.12065 0.2794)
			(end -0.12065 0.3048)
			(stroke
				(width 0.1)
				(type default)
			)
			(layer "F.Fab")
		)
		(fp_line
			(start -0.12065 -0.2794)
			(end 0.12065 -0.2794)
			(stroke
				(width 0.1)
				(type default)
			)
			(layer "F.Fab")
		)
		(fp_line
			(start -0.12065 -0.305054)
			(end -0.12065 -0.2794)
			(stroke
				(width 0.1)
				(type default)
			)
			(layer "F.Fab")
		)
		(fp_line
			(start -0.67945 0.3048)
			(end -0.67945 -0.305054)
			(stroke
				(width 0.1)
				(type default)
			)
			(layer "F.Fab")
		)
		(fp_line
			(start -0.67945 -0.305054)
			(end -0.12065 -0.305054)
			(stroke
				(width 0.1)
				(type default)
			)
			(layer "F.Fab")
		)
		(pad "1" smd circle
			(at -0.40005 0 180)
			(size 0 0)
			(layers "F.Cu" "F.Mask" "F.Paste")
			(net "SMB_SML1_PMBUS_HSC_SCL")
		)
		(pad "2" smd circle
			(at 0.40005 0 180)
			(size 0 0)
			(layers "F.Cu" "F.Mask" "F.Paste")
			(net "SMB_SML1_PMBUS_HSC_R1_SCL")
		)
	)
)
